(kicad_pcb
	(version 20240108)
	(generator "pcbnew")
	(generator_version "8.0")
	(general
		(thickness 1.586)
		(legacy_teardrops no)
	)
	(paper "A4")
	(title_block
		(title "GMSL Serializer")
		(date "2024-11-27")
		(rev "1.1.1")
		(company "Antmicro Ltd")
		(comment 1 "www.antmicro.com")
		(comment 9 "footprints 10-14 of 117")
	)
	(layers
		(0 "F.Cu" signal)
		(1 "In1.Cu" power)
		(2 "In2.Cu" power)
		(31 "B.Cu" signal)
		(32 "B.Adhes" user "B.Adhesive")
		(33 "F.Adhes" user "F.Adhesive")
		(34 "B.Paste" user)
		(35 "F.Paste" user)
		(36 "B.SilkS" user "B.Silkscreen")
		(37 "F.SilkS" user "F.Silkscreen")
		(38 "B.Mask" user)
		(39 "F.Mask" user)
		(40 "Dwgs.User" user "User.Drawings")
		(41 "Cmts.User" user "User.Comments")
		(42 "Eco1.User" user "User.Eco1")
		(43 "Eco2.User" user "User.Eco2")
		(44 "Edge.Cuts" user)
		(45 "Margin" user)
		(46 "B.CrtYd" user "B.Courtyard")
		(47 "F.CrtYd" user "F.Courtyard")
		(48 "B.Fab" user)
		(49 "F.Fab" user)
	)
	(footprint "antmicro-footprints:R_0402_1005Metric"
		(layer "F.Cu")
		(at 144.74 79.700142 -90)
		(descr "Resistor SMD 0402")
		(tags "resistor SMD 0402")
		(property "Reference" "R41"
			(at -1.050142 -0.51 90)
			(layer "F.SilkS")
			(effects
				(font
					(size 0.7 0.7)
					(thickness 0.15)
				)
				(justify right top)
			)
		)
		(property "Value" "R_10k_0402"
			(at -1.011843 1.772047 90)
			(layer "F.Fab")
			(effects
				(font
					(size 0.7 0.7)
					(thickness 0.15)
				)
				(justify right top)
			)
		)
		(property "Footprint" "antmicro-footprints:R_0402_1005Metric"
			(at 0 0 90)
			(layer "F.Fab")
			(hide yes)
			(effects
				(font
					(size 1.27 1.27)
					(thickness 0.15)
				)
			)
		)
		(property "Datasheet" "https://www.bourns.com/docs/product-datasheets/cr.pdf"
			(at 0 0 90)
			(layer "F.Fab")
			(hide yes)
			(effects
				(font
					(size 1.27 1.27)
					(thickness 0.15)
				)
			)
		)
		(property "MPN" "CR0402-FX-1002GLF"
			(at 0 0 -90)
			(unlocked yes)
			(layer "F.Fab")
			(hide yes)
			(effects
				(font
					(size 1 1)
					(thickness 0.15)
				)
			)
		)
		(property "Manufacturer" "Bourns"
			(at 0 0 -90)
			(unlocked yes)
			(layer "F.Fab")
			(hide yes)
			(effects
				(font
					(size 1 1)
					(thickness 0.15)
				)
			)
		)
		(property "License" "Apache-2.0"
			(at 0 0 -90)
			(unlocked yes)
			(layer "F.Fab")
			(hide yes)
			(effects
				(font
					(size 1 1)
					(thickness 0.15)
				)
			)
		)
		(property "Author" "Antmicro"
			(at 0 0 -90)
			(unlocked yes)
			(layer "F.Fab")
			(hide yes)
			(effects
				(font
					(size 1 1)
					(thickness 0.15)
				)
			)
		)
		(property "Val" "10k"
			(at 0 0 -90)
			(unlocked yes)
			(layer "F.Fab")
			(hide yes)
			(effects
				(font
					(size 1 1)
					(thickness 0.15)
				)
			)
		)
		(property "Tolerance" "1%"
			(at 0 0 -90)
			(unlocked yes)
			(layer "F.Fab")
			(hide yes)
			(effects
				(font
					(size 1 1)
					(thickness 0.15)
				)
			)
		)
		(sheetname "Supply")
		(sheetfile "supply.kicad_sch")
		(attr smd)
		(fp_rect
			(start -0.925 -0.47)
			(end 0.925 0.47)
			(stroke
				(width 0.05)
				(type default)
			)
			(fill none)
			(layer "F.CrtYd")
		)
		(fp_rect
			(start -0.5 -0.25)
			(end 0.5 0.25)
			(stroke
				(width 0.15)
				(type solid)
			)
			(fill none)
			(layer "F.Fab")
		)
		(fp_text user "License: Apache-2.0"
			(at -0.95 5.169 90)
			(layer "F.Fab")
			(hide yes)
			(effects
				(font
					(size 0.7 0.7)
					(thickness 0.15)
				)
				(justify right top)
			)
		)
		(fp_text user "Author: Antmicro"
			(at -0.95 4.169 90)
			(layer "F.Fab")
			(hide yes)
			(effects
				(font
					(size 0.7 0.7)
					(thickness 0.15)
				)
				(justify right top)
			)
		)
		(fp_text user "${REFERENCE}"
			(at -0.95 3.168 90)
			(layer "F.Fab")
			(hide yes)
			(effects
				(font
					(size 0.7 0.7)
					(thickness 0.15)
				)
				(justify right top)
			)
		)
		(pad "1" smd roundrect
			(at -0.48 0 270)
			(size 0.59 0.64)
			(layers "F.Cu" "F.Paste" "F.Mask")
			(roundrect_rratio 0.25)
			(net 97 "/Supply/EN_3V3")
			(pintype "passive")
		)
		(pad "2" smd roundrect
			(at 0.48 0 270)
			(size 0.59 0.64)
			(layers "F.Cu" "F.Paste" "F.Mask")
			(roundrect_rratio 0.25)
			(net 2 "+12V")
			(pintype "passive")
		)
	)
	(footprint "antmicro-footprints:C_0402_1005Metric"
		(layer "F.Cu")
		(at 160.208 106.394 -90)
		(descr "Capacitor SMD 0402")
		(tags "capacitor SMD 0402")
		(property "Reference" "C14"
			(at 0.956 -0.392 90)
			(layer "F.SilkS")
			(effects
				(font
					(size 0.7 0.7)
					(thickness 0.15)
				)
				(justify right bottom)
			)
		)
		(property "Value" "C_1u_16V_0402"
			(at -1.022927 2.155213 90)
			(layer "F.Fab")
			(effects
				(font
					(size 0.7 0.7)
					(thickness 0.15)
				)
				(justify right bottom)
			)
		)
		(property "Footprint" "antmicro-footprints:C_0402_1005Metric"
			(at 0 0 -90)
			(layer "F.Fab")
			(hide yes)
			(effects
				(font
					(size 1.27 1.27)
					(thickness 0.15)
				)
			)
		)
		(property "Datasheet" "https://www.kemet.com/en/us/capacitors/product/C0402C105M4PACTU.html"
			(at 0 0 -90)
			(layer "F.Fab")
			(hide yes)
			(effects
				(font
					(size 1.27 1.27)
					(thickness 0.15)
				)
			)
		)
		(property "Author" "Antmicro"
			(at 53.814 266.602 0)
			(layer "F.Fab")
			(hide yes)
			(effects
				(font
					(size 1 1)
					(thickness 0.15)
				)
			)
		)
		(property "Dielectric" ""
			(at 53.814 266.602 0)
			(layer "F.Fab")
			(hide yes)
			(effects
				(font
					(size 1 1)
					(thickness 0.15)
				)
			)
		)
		(property "License" "Apache-2.0"
			(at 53.814 266.602 0)
			(layer "F.Fab")
			(hide yes)
			(effects
				(font
					(size 1 1)
					(thickness 0.15)
				)
			)
		)
		(property "MPN" "C0402C105M4PACTU"
			(at 53.814 266.602 0)
			(layer "F.Fab")
			(hide yes)
			(effects
				(font
					(size 1 1)
					(thickness 0.15)
				)
			)
		)
		(property "Manufacturer" "KEMET"
			(at 53.814 266.602 0)
			(layer "F.Fab")
			(hide yes)
			(effects
				(font
					(size 1 1)
					(thickness 0.15)
				)
			)
		)
		(property "Val" "1u"
			(at 53.814 266.602 0)
			(layer "F.Fab")
			(hide yes)
			(effects
				(font
					(size 1 1)
					(thickness 0.15)
				)
			)
		)
		(property "Voltage" "16V"
			(at 53.814 266.602 0)
			(layer "F.Fab")
			(hide yes)
			(effects
				(font
					(size 1 1)
					(thickness 0.15)
				)
			)
		)
		(sheetname "Supply")
		(sheetfile "supply.kicad_sch")
		(attr smd)
		(fp_rect
			(start -0.925 -0.47)
			(end 0.925 0.47)
			(stroke
				(width 0.05)
				(type default)
			)
			(fill none)
			(layer "F.CrtYd")
		)
		(fp_line
			(start -0.494 0.248)
			(end -0.494 -0.25)
			(stroke
				(width 0.15)
				(type solid)
			)
			(layer "F.Fab")
		)
		(fp_line
			(start 0.504 0.248)
			(end -0.494 0.248)
			(stroke
				(width 0.15)
				(type solid)
			)
			(layer "F.Fab")
		)
		(fp_line
			(start -0.494 -0.25)
			(end 0.504 -0.25)
			(stroke
				(width 0.15)
				(type solid)
			)
			(layer "F.Fab")
		)
		(fp_line
			(start 0.504 -0.25)
			(end 0.504 0.248)
			(stroke
				(width 0.15)
				(type solid)
			)
			(layer "F.Fab")
		)
		(fp_text user "${REFERENCE}"
			(at -0.939 4.599 90)
			(layer "F.Fab")
			(hide yes)
			(effects
				(font
					(size 0.7 0.7)
					(thickness 0.15)
				)
				(justify right bottom)
			)
		)
		(fp_text user "Author: Antmicro"
			(at -0.939 3.399 90)
			(layer "F.Fab")
			(hide yes)
			(effects
				(font
					(size 0.7 0.7)
					(thickness 0.15)
				)
				(justify right bottom)
			)
		)
		(fp_text user "License: Apache-2.0"
			(at -0.939 5.799 90)
			(layer "F.Fab")
			(hide yes)
			(effects
				(font
					(size 0.7 0.7)
					(thickness 0.15)
				)
				(justify right bottom)
			)
		)
		(pad "1" smd roundrect
			(at -0.48 0 270)
			(size 0.59 0.64)
			(layers "F.Cu" "F.Paste" "F.Mask")
			(roundrect_rratio 0.25)
			(net 1 "GND")
			(pintype "passive")
		)
		(pad "2" smd roundrect
			(at 0.48 0 270)
			(size 0.59 0.64)
			(layers "F.Cu" "F.Paste" "F.Mask")
			(roundrect_rratio 0.25)
			(net 11 "+1V8")
			(pintype "passive")
		)
	)
	(footprint "antmicro-footprints:C_0402_1005Metric"
		(layer "F.Cu")
		(at 165.55 86.473 -90)
		(descr "Capacitor SMD 0402")
		(tags "capacitor SMD 0402")
		(property "Reference" "C10"
			(at -3.035 -0.495 90)
			(layer "F.SilkS")
			(effects
				(font
					(size 0.7 0.7)
					(thickness 0.15)
				)
				(justify right bottom)
			)
		)
		(property "Value" "C_100n_0402"
			(at -1.022927 2.155213 90)
			(layer "F.Fab")
			(effects
				(font
					(size 0.7 0.7)
					(thickness 0.15)
				)
				(justify right bottom)
			)
		)
		(property "Footprint" "antmicro-footprints:C_0402_1005Metric"
			(at 0 0 -90)
			(layer "F.Fab")
			(hide yes)
			(effects
				(font
					(size 1.27 1.27)
					(thickness 0.15)
				)
			)
		)
		(property "Datasheet" "https://www.murata.com/products/productdetail?partno=GRM155R61H104KE14%23"
			(at 0 0 -90)
			(layer "F.Fab")
			(hide yes)
			(effects
				(font
					(size 1.27 1.27)
					(thickness 0.15)
				)
			)
		)
		(property "Author" "Antmicro"
			(at 79.077 252.023 0)
			(layer "F.Fab")
			(hide yes)
			(effects
				(font
					(size 1 1)
					(thickness 0.15)
				)
			)
		)
		(property "Dielectric" "X5R"
			(at 79.077 252.023 0)
			(layer "F.Fab")
			(hide yes)
			(effects
				(font
					(size 1 1)
					(thickness 0.15)
				)
			)
		)
		(property "License" "Apache-2.0"
			(at 79.077 252.023 0)
			(layer "F.Fab")
			(hide yes)
			(effects
				(font
					(size 1 1)
					(thickness 0.15)
				)
			)
		)
		(property "MPN" "GRM155R61H104KE14D"
			(at 79.077 252.023 0)
			(layer "F.Fab")
			(hide yes)
			(effects
				(font
					(size 1 1)
					(thickness 0.15)
				)
			)
		)
		(property "Manufacturer" "Murata"
			(at 79.077 252.023 0)
			(layer "F.Fab")
			(hide yes)
			(effects
				(font
					(size 1 1)
					(thickness 0.15)
				)
			)
		)
		(property "Val" "100n"
			(at 79.077 252.023 0)
			(layer "F.Fab")
			(hide yes)
			(effects
				(font
					(size 1 1)
					(thickness 0.15)
				)
			)
		)
		(property "Voltage" "50V"
			(at 79.077 252.023 0)
			(layer "F.Fab")
			(hide yes)
			(effects
				(font
					(size 1 1)
					(thickness 0.15)
				)
			)
		)
		(sheetname "GMSL Connector")
		(sheetfile "GMSL.kicad_sch")
		(attr smd)
		(fp_rect
			(start -0.925 -0.47)
			(end 0.925 0.47)
			(stroke
				(width 0.05)
				(type default)
			)
			(fill none)
			(layer "F.CrtYd")
		)
		(fp_line
			(start -0.494 0.248)
			(end -0.494 -0.25)
			(stroke
				(width 0.15)
				(type solid)
			)
			(layer "F.Fab")
		)
		(fp_line
			(start 0.504 0.248)
			(end -0.494 0.248)
			(stroke
				(width 0.15)
				(type solid)
			)
			(layer "F.Fab")
		)
		(fp_line
			(start -0.494 -0.25)
			(end 0.504 -0.25)
			(stroke
				(width 0.15)
				(type solid)
			)
			(layer "F.Fab")
		)
		(fp_line
			(start 0.504 -0.25)
			(end 0.504 0.248)
			(stroke
				(width 0.15)
				(type solid)
			)
			(layer "F.Fab")
		)
		(fp_text user "Author: Antmicro"
			(at -0.939 3.399 90)
			(layer "F.Fab")
			(hide yes)
			(effects
				(font
					(size 0.7 0.7)
					(thickness 0.15)
				)
				(justify right bottom)
			)
		)
		(fp_text user "${REFERENCE}"
			(at -0.939 4.599 90)
			(layer "F.Fab")
			(hide yes)
			(effects
				(font
					(size 0.7 0.7)
					(thickness 0.15)
				)
				(justify right bottom)
			)
		)
		(fp_text user "License: Apache-2.0"
			(at -0.939 5.799 90)
			(layer "F.Fab")
			(hide yes)
			(effects
				(font
					(size 0.7 0.7)
					(thickness 0.15)
				)
				(justify right bottom)
			)
		)
		(pad "1" smd roundrect
			(at -0.48 0 270)
			(size 0.59 0.64)
			(layers "F.Cu" "F.Paste" "F.Mask")
			(roundrect_rratio 0.25)
			(net 1 "GND")
			(pintype "passive")
		)
		(pad "2" smd roundrect
			(at 0.48 0 270)
			(size 0.59 0.64)
			(layers "F.Cu" "F.Paste" "F.Mask")
			(roundrect_rratio 0.25)
			(net 2 "+12V")
			(pintype "passive")
		)
	)
	(footprint "antmicro-footprints:C_0402_1005Metric"
		(layer "F.Cu")
		(at 136.58 85.647 -90)
		(descr "Capacitor SMD 0402")
		(tags "capacitor SMD 0402")
		(property "Reference" "C7"
			(at 0.823 -1.78 90)
			(layer "F.SilkS")
			(effects
				(font
					(size 0.7 0.7)
					(thickness 0.15)
				)
				(justify right bottom)
			)
		)
		(property "Value" "C_22u_0402"
			(at -1.022927 2.155213 90)
			(layer "F.Fab")
			(effects
				(font
					(size 0.7 0.7)
					(thickness 0.15)
				)
				(justify right bottom)
			)
		)
		(property "Footprint" "antmicro-footprints:C_0402_1005Metric"
			(at 0 0 -90)
			(layer "F.Fab")
			(hide yes)
			(effects
				(font
					(size 1.27 1.27)
					(thickness 0.15)
				)
			)
		)
		(property "Datasheet" "https://www.murata.com/products/productdetail?partno=GRM158R60J226ME01%23"
			(at 0 0 -90)
			(layer "F.Fab")
			(hide yes)
			(effects
				(font
					(size 1.27 1.27)
					(thickness 0.15)
				)
			)
		)
		(property "Author" "Antmicro"
			(at 52.853 223.847 0)
			(layer "F.Fab")
			(hide yes)
			(effects
				(font
					(size 1 1)
					(thickness 0.15)
				)
			)
		)
		(property "Dielectric" ""
			(at 52.853 223.847 0)
			(layer "F.Fab")
			(hide yes)
			(effects
				(font
					(size 1 1)
					(thickness 0.15)
				)
			)
		)
		(property "License" "Apache-2.0"
			(at 52.853 223.847 0)
			(layer "F.Fab")
			(hide yes)
			(effects
				(font
					(size 1 1)
					(thickness 0.15)
				)
			)
		)
		(property "MPN" "GRM158R60J226ME01D"
			(at 52.853 223.847 0)
			(layer "F.Fab")
			(hide yes)
			(effects
				(font
					(size 1 1)
					(thickness 0.15)
				)
			)
		)
		(property "Manufacturer" "Murata"
			(at 52.853 223.847 0)
			(layer "F.Fab")
			(hide yes)
			(effects
				(font
					(size 1 1)
					(thickness 0.15)
				)
			)
		)
		(property "Val" "22u"
			(at 52.853 223.847 0)
			(layer "F.Fab")
			(hide yes)
			(effects
				(font
					(size 1 1)
					(thickness 0.15)
				)
			)
		)
		(property "Voltage" ""
			(at 52.853 223.847 0)
			(layer "F.Fab")
			(hide yes)
			(effects
				(font
					(size 1 1)
					(thickness 0.15)
				)
			)
		)
		(sheetname "Supply")
		(sheetfile "supply.kicad_sch")
		(attr smd)
		(fp_rect
			(start -0.925 -0.47)
			(end 0.925 0.47)
			(stroke
				(width 0.05)
				(type default)
			)
			(fill none)
			(layer "F.CrtYd")
		)
		(fp_line
			(start -0.494 0.248)
			(end -0.494 -0.25)
			(stroke
				(width 0.15)
				(type solid)
			)
			(layer "F.Fab")
		)
		(fp_line
			(start 0.504 0.248)
			(end -0.494 0.248)
			(stroke
				(width 0.15)
				(type solid)
			)
			(layer "F.Fab")
		)
		(fp_line
			(start -0.494 -0.25)
			(end 0.504 -0.25)
			(stroke
				(width 0.15)
				(type solid)
			)
			(layer "F.Fab")
		)
		(fp_line
			(start 0.504 -0.25)
			(end 0.504 0.248)
			(stroke
				(width 0.15)
				(type solid)
			)
			(layer "F.Fab")
		)
		(fp_text user "Author: Antmicro"
			(at -0.939 3.399 90)
			(layer "F.Fab")
			(hide yes)
			(effects
				(font
					(size 0.7 0.7)
					(thickness 0.15)
				)
				(justify right bottom)
			)
		)
		(fp_text user "License: Apache-2.0"
			(at -0.939 5.799 90)
			(layer "F.Fab")
			(hide yes)
			(effects
				(font
					(size 0.7 0.7)
					(thickness 0.15)
				)
				(justify right bottom)
			)
		)
		(fp_text user "${REFERENCE}"
			(at -0.939 4.599 90)
			(layer "F.Fab")
			(hide yes)
			(effects
				(font
					(size 0.7 0.7)
					(thickness 0.15)
				)
				(justify right bottom)
			)
		)
		(pad "1" smd roundrect
			(at -0.48 0 270)
			(size 0.59 0.64)
			(layers "F.Cu" "F.Paste" "F.Mask")
			(roundrect_rratio 0.25)
			(net 1 "GND")
			(pintype "passive")
		)
		(pad "2" smd roundrect
			(at 0.48 0 270)
			(size 0.59 0.64)
			(layers "F.Cu" "F.Paste" "F.Mask")
			(roundrect_rratio 0.25)
			(net 7 "/Supply/OUT_5V")
			(pintype "passive")
		)
	)
	(footprint "antmicro-footprints:R_0402_1005Metric"
		(layer "F.Cu")
		(at 140.83 81.060142 180)
		(descr "Resistor SMD 0402")
		(tags "resistor SMD 0402")
		(property "Reference" "R37"
			(at 0.69 0.590142 0)
			(layer "F.SilkS")
			(effects
				(font
					(size 0.7 0.7)
					(thickness 0.15)
				)
				(justify right top)
			)
		)
		(property "Value" "R_31k6_0402"
			(at -1.011843 1.772047 0)
			(layer "F.Fab")
			(effects
				(font
					(size 0.7 0.7)
					(thickness 0.15)
				)
				(justify right top)
			)
		)
		(property "Footprint" "antmicro-footprints:R_0402_1005Metric"
			(at 0 0 0)
			(layer "F.Fab")
			(hide yes)
			(effects
				(font
					(size 1.27 1.27)
					(thickness 0.15)
				)
			)
		)
		(property "Datasheet" "https://www.bourns.com/docs/product-datasheets/cr.pdf"
			(at 0 0 0)
			(layer "F.Fab")
			(hide yes)
			(effects
				(font
					(size 1.27 1.27)
					(thickness 0.15)
				)
			)
		)
		(property "Description" "SMD Chip Resistor"
			(at 0 0 0)
			(layer "F.Fab")
			(hide yes)
			(effects
				(font
					(size 1.27 1.27)
					(thickness 0.15)
				)
			)
		)
		(property "MPN" "CR0402-FX-3162GLF"
			(at 0 0 180)
			(unlocked yes)
			(layer "F.Fab")
			(hide yes)
			(effects
				(font
					(size 1 1)
					(thickness 0.15)
				)
			)
		)
		(property "Manufacturer" "Bourns"
			(at 0 0 180)
			(unlocked yes)
			(layer "F.Fab")
			(hide yes)
			(effects
				(font
					(size 1 1)
					(thickness 0.15)
				)
			)
		)
		(property "License" "Apache-2.0"
			(at 0 0 180)
			(unlocked yes)
			(layer "F.Fab")
			(hide yes)
			(effects
				(font
					(size 1 1)
					(thickness 0.15)
				)
			)
		)
		(property "Author" "Antmicro"
			(at 0 0 180)
			(unlocked yes)
			(layer "F.Fab")
			(hide yes)
			(effects
				(font
					(size 1 1)
					(thickness 0.15)
				)
			)
		)
		(property "Val" "31k6"
			(at 0 0 180)
			(unlocked yes)
			(layer "F.Fab")
			(hide yes)
			(effects
				(font
					(size 1 1)
					(thickness 0.15)
				)
			)
		)
		(property "Tolerance" "1%"
			(at 0 0 180)
			(unlocked yes)
			(layer "F.Fab")
			(hide yes)
			(effects
				(font
					(size 1 1)
					(thickness 0.15)
				)
			)
		)
		(sheetname "Supply")
		(sheetfile "supply.kicad_sch")
		(attr smd)
		(fp_rect
			(start -0.925 -0.47)
			(end 0.925 0.47)
			(stroke
				(width 0.05)
				(type default)
			)
			(fill none)
			(layer "F.CrtYd")
		)
		(fp_rect
			(start -0.5 -0.25)
			(end 0.5 0.25)
			(stroke
				(width 0.15)
				(type solid)
			)
			(fill none)
			(layer "F.Fab")
		)
		(fp_text user "Author: Antmicro"
			(at -0.95 4.169 0)
			(layer "F.Fab")
			(hide yes)
			(effects
				(font
					(size 0.7 0.7)
					(thickness 0.15)
				)
				(justify right top)
			)
		)
		(fp_text user "${REFERENCE}"
			(at -0.95 3.168 0)
			(layer "F.Fab")
			(hide yes)
			(effects
				(font
					(size 0.7 0.7)
					(thickness 0.15)
				)
				(justify right top)
			)
		)
		(fp_text user "License: Apache-2.0"
			(at -0.95 5.169 0)
			(layer "F.Fab")
			(hide yes)
			(effects
				(font
					(size 0.7 0.7)
					(thickness 0.15)
				)
				(justify right top)
			)
		)
		(pad "1" smd roundrect
			(at -0.48 0 180)
			(size 0.59 0.64)
			(layers "F.Cu" "F.Paste" "F.Mask")
			(roundrect_rratio 0.25)
			(net 96 "/Supply/FB_3V3")
			(pintype "passive")
		)
		(pad "2" smd roundrect
			(at 0.48 0 180)
			(size 0.59 0.64)
			(layers "F.Cu" "F.Paste" "F.Mask")
			(roundrect_rratio 0.25)
			(net 94 "/Supply/OUT_3V3")
			(pintype "passive")
		)
	)
)
